# SCM (Grand Teton) — schematic netlist excerpt (pin names and nets, part order shuffled) for the footprints in the layout excerpt that follows; sources: Cadence DE-HDL packaged netlist, KiCad conversion of 12092022_DA0F0TMDCD0_F0T_Management_Board_D_brd_V3_OCP.brd

R777  Q_RES  200K 1% CHIP  pkg 0402LF  page 15 : A = P3V_BAT_R ; B = P3V_BAT_R1
R731  Q_RES  0 5% CHIP  pkg 0402LF  page 29 : A = SMB_DEBUG_AUX_LVC3_USB_SDA ; B = SMB_DEBUG_AUX_LVC3_USB_R2_SDA

(kicad_pcb
	(version 20260206)
	(generator "pcbnew")
	(generator_version "10.0")
	(general
		(thickness 1.6)
		(legacy_teardrops no)
	)
	(paper "A4")
	(title_block
		(title "12092022_DA0F0TMDCD0_F0T_Management_Board_D_brd_V3_OCP.brd")
		(comment 1 "Grand Teton / footprints 1428-1429 of 1440")
	)
	(layers
		(0 "F.Cu" signal "TOP")
		(4 "In1.Cu" signal "GND")
		(6 "In2.Cu" signal "IN1")
		(8 "In3.Cu" signal "GND1")
		(10 "In4.Cu" signal "IN2")
		(12 "In5.Cu" signal "VCC")
		(14 "In6.Cu" signal "VCC1")
		(16 "In7.Cu" signal "IN3")
		(18 "In8.Cu" signal "GND2")
		(20 "In9.Cu" signal "IN4")
		(22 "In10.Cu" signal "GND3")
		(2 "B.Cu" signal "BOTTOM")
		(9 "F.Adhes" user "F.Adhesive")
		(11 "B.Adhes" user "B.Adhesive")
		(13 "F.Paste" user "Package Geometry/Pastemask Top")
		(15 "B.Paste" user "Package Geometry/Pastemask Bottom")
		(5 "F.SilkS" user "Ref Des/Silkscreen Top")
		(7 "B.SilkS" user "Ref Des/Silkscreen Bottom")
		(1 "F.Mask" user "Board Geometry/Soldermask Top")
		(3 "B.Mask" user "Board Geometry/Soldermask Bottom")
		(17 "Dwgs.User" user "User.Drawings")
		(19 "Cmts.User" user "User.Comments")
		(21 "Eco1.User" user "User.Eco1")
		(23 "Eco2.User" user "User.Eco2")
		(25 "Edge.Cuts" user "Board Geometry/Outline")
		(27 "Margin" user)
		(31 "F.CrtYd" user "Package Geometry/Place Bound Top")
		(29 "B.CrtYd" user "Package Geometry/Place Bound Bottom")
		(35 "F.Fab" user "Ref Des/Assembly Top")
		(33 "B.Fab" user "Ref Des/Assembly Bottom")
	)
	(footprint ""
		(layer "B.Cu")
		(at 36.77412 -97.22104 180)
		(property "Reference" "R731"
			(at 0 0 0)
			(layer "B.SilkS")
			(hide yes)
			(effects
				(font
					(size 1.27 1.27)
				)
				(justify mirror)
			)
		)
		(property "Value" ""
			(at 0 0 0)
			(layer "B.Fab")
			(effects
				(font
					(size 1.27 1.27)
				)
				(justify mirror)
			)
		)
		(duplicate_pad_numbers_are_jumpers no)
		(fp_line
			(start 0.7874 0.4064)
			(end 0.7874 -0.4064)
			(stroke
				(width 0.1524)
				(type default)
			)
			(layer "B.SilkS")
		)
		(fp_line
			(start 0.7874 -0.4064)
			(end -0.7874 -0.4064)
			(stroke
				(width 0.1524)
				(type default)
			)
			(layer "B.SilkS")
		)
		(fp_line
			(start -0.7874 0.4064)
			(end 0.7874 0.4064)
			(stroke
				(width 0.1524)
				(type default)
			)
			(layer "B.SilkS")
		)
		(fp_line
			(start -0.7874 -0.4064)
			(end -0.7874 0.4064)
			(stroke
				(width 0.1524)
				(type default)
			)
			(layer "B.SilkS")
		)
		(fp_line
			(start 0.67945 0.3048)
			(end 0.67945 -0.305054)
			(stroke
				(width 0.1)
				(type default)
			)
			(layer "B.Fab")
		)
		(fp_line
			(start 0.67945 -0.305054)
			(end 0.12065 -0.305054)
			(stroke
				(width 0.1)
				(type default)
			)
			(layer "B.Fab")
		)
		(fp_line
			(start 0.12065 0.3048)
			(end 0.67945 0.3048)
			(stroke
				(width 0.1)
				(type default)
			)
			(layer "B.Fab")
		)
		(fp_line
			(start 0.12065 0.2794)
			(end 0.12065 0.3048)
			(stroke
				(width 0.1)
				(type default)
			)
			(layer "B.Fab")
		)
		(fp_line
			(start 0.12065 -0.2794)
			(end -0.12065 -0.2794)
			(stroke
				(width 0.1)
				(type default)
			)
			(layer "B.Fab")
		)
		(fp_line
			(start 0.12065 -0.305054)
			(end 0.12065 -0.2794)
			(stroke
				(width 0.1)
				(type default)
			)
			(layer "B.Fab")
		)
		(fp_line
			(start -0.120396 0.3048)
			(end -0.120396 0.2794)
			(stroke
				(width 0.1)
				(type default)
			)
			(layer "B.Fab")
		)
		(fp_line
			(start -0.120396 0.2794)
			(end 0.12065 0.2794)
			(stroke
				(width 0.1)
				(type default)
			)
			(layer "B.Fab")
		)
		(fp_line
			(start -0.12065 -0.2794)
			(end -0.12065 -0.3048)
			(stroke
				(width 0.1)
				(type default)
			)
			(layer "B.Fab")
		)
		(fp_line
			(start -0.12065 -0.3048)
			(end -0.67945 -0.3048)
			(stroke
				(width 0.1)
				(type default)
			)
			(layer "B.Fab")
		)
		(fp_line
			(start -0.67945 0.3048)
			(end -0.120396 0.3048)
			(stroke
				(width 0.1)
				(type default)
			)
			(layer "B.Fab")
		)
		(fp_line
			(start -0.67945 -0.3048)
			(end -0.67945 0.3048)
			(stroke
				(width 0.1)
				(type default)
			)
			(layer "B.Fab")
		)
		(pad "1" smd circle
			(at 0.40005 0)
			(size 0 0)
			(layers "B.Cu" "B.Mask" "B.Paste")
			(net "SMB_DEBUG_AUX_LVC3_USB_SDA")
		)
		(pad "2" smd circle
			(at -0.40005 0)
			(size 0 0)
			(layers "B.Cu" "B.Mask" "B.Paste")
			(net "SMB_DEBUG_AUX_LVC3_USB_R2_SDA")
		)
	)
	(footprint ""
		(layer "B.Cu")
		(at 42.909236 -71.589392)
		(property "Reference" "R777"
			(at 0 0 0)
			(layer "B.SilkS")
			(hide yes)
			(effects
				(font
					(size 1.27 1.27)
				)
				(justify mirror)
			)
		)
		(property "Value" ""
			(at 0 0 0)
			(layer "B.Fab")
			(effects
				(font
					(size 1.27 1.27)
				)
				(justify mirror)
			)
		)
		(duplicate_pad_numbers_are_jumpers no)
		(fp_line
			(start -0.7874 -0.4064)
			(end -0.7874 0.4064)
			(stroke
				(width 0.1524)
				(type default)
			)
			(layer "B.SilkS")
		)
		(fp_line
			(start -0.7874 0.4064)
			(end 0.7874 0.4064)
			(stroke
				(width 0.1524)
				(type default)
			)
			(layer "B.SilkS")
		)
		(fp_line
			(start 0.7874 -0.4064)
			(end -0.7874 -0.4064)
			(stroke
				(width 0.1524)
				(type default)
			)
			(layer "B.SilkS")
		)
		(fp_line
			(start 0.7874 0.4064)
			(end 0.7874 -0.4064)
			(stroke
				(width 0.1524)
				(type default)
			)
			(layer "B.SilkS")
		)
		(fp_line
			(start -0.67945 -0.3048)
			(end -0.67945 0.3048)
			(stroke
				(width 0.1)
				(type default)
			)
			(layer "B.Fab")
		)
		(fp_line
			(start -0.67945 0.3048)
			(end -0.120396 0.3048)
			(stroke
				(width 0.1)
				(type default)
			)
			(layer "B.Fab")
		)
		(fp_line
			(start -0.12065 -0.3048)
			(end -0.67945 -0.3048)
			(stroke
				(width 0.1)
				(type default)
			)
			(layer "B.Fab")
		)
		(fp_line
			(start -0.12065 -0.2794)
			(end -0.12065 -0.3048)
			(stroke
				(width 0.1)
				(type default)
			)
			(layer "B.Fab")
		)
		(fp_line
			(start -0.120396 0.2794)
			(end 0.12065 0.2794)
			(stroke
				(width 0.1)
				(type default)
			)
			(layer "B.Fab")
		)
		(fp_line
			(start -0.120396 0.3048)
			(end -0.120396 0.2794)
			(stroke
				(width 0.1)
				(type default)
			)
			(layer "B.Fab")
		)
		(fp_line
			(start 0.12065 -0.305054)
			(end 0.12065 -0.2794)
			(stroke
				(width 0.1)
				(type default)
			)
			(layer "B.Fab")
		)
		(fp_line
			(start 0.12065 -0.2794)
			(end -0.12065 -0.2794)
			(stroke
				(width 0.1)
				(type default)
			)
			(layer "B.Fab")
		)
		(fp_line
			(start 0.12065 0.2794)
			(end 0.12065 0.3048)
			(stroke
				(width 0.1)
				(type default)
			)
			(layer "B.Fab")
		)
		(fp_line
			(start 0.12065 0.3048)
			(end 0.67945 0.3048)
			(stroke
				(width 0.1)
				(type default)
			)
			(layer "B.Fab")
		)
		(fp_line
			(start 0.67945 -0.305054)
			(end 0.12065 -0.305054)
			(stroke
				(width 0.1)
				(type default)
			)
			(layer "B.Fab")
		)
		(fp_line
			(start 0.67945 0.3048)
			(end 0.67945 -0.305054)
			(stroke
				(width 0.1)
				(type default)
			)
			(layer "B.Fab")
		)
		(pad "1" smd circle
			(at 0.40005 0 180)
			(size 0 0)
			(layers "B.Cu" "B.Mask" "B.Paste")
			(net "P3V_BAT_R")
		)
		(pad "2" smd circle
			(at -0.40005 0 180)
			(size 0 0)
			(layers "B.Cu" "B.Mask" "B.Paste")
			(net "P3V_BAT_R1")
		)
	)
)
